# T6G (Grand Teton) — schematic netlist excerpt (pin names and nets, part order shuffled) for the footprints in the layout excerpt that follows; sources: Cadence DE-HDL packaged netlist, KiCad conversion of 04192023_DAF0TMB3IC0_F0TG_MB_C_brd_V02_OCP.brd

C260  Q_CAP  0.1UF 10V 10% X7S  pkg C0201  page 323 : A = P0V9_CPU1_RT0_2A ; B = GND
C228  Q_CAP  0.1UF 10V 10% X7S  pkg C0201  page 323 : A = P0V9_CPU1_RT0_2A ; B = GND
R1265  Q_RES  10K 5% CHIP  pkg 0402LF  page 167 : A = FM_BIOS_USB_RECOVERY ; B = GND
C493  Q_CAP  0.1UF 10V 10% X7S  pkg C0201  page 356 : A = P0V9_CPU1_RT_2D ; B = GND
C777  Q_CAP  0.1UF 10V 10% X7S  pkg C0201  page 301 : A = P1V8_CPU0_RT2_1A ; B = GND

(kicad_pcb
	(version 20260206)
	(generator "pcbnew")
	(generator_version "10.0")
	(general
		(thickness 1.6)
		(legacy_teardrops no)
	)
	(paper "A4")
	(title_block
		(title "04192023_DAF0TMB3IC0_F0TG_MB_C_brd_V02_OCP.brd")
		(comment 1 "Grand Teton / footprints 7177-7181 of 8354")
	)
	(layers
		(0 "F.Cu" signal "TOP")
		(4 "In1.Cu" signal "GND")
		(6 "In2.Cu" signal "IN1")
		(8 "In3.Cu" signal "GND1")
		(10 "In4.Cu" signal "IN2")
		(12 "In5.Cu" signal "GND2")
		(14 "In6.Cu" signal "IN3")
		(16 "In7.Cu" signal "GND3")
		(18 "In8.Cu" signal "VCC")
		(20 "In9.Cu" signal "VCC1")
		(22 "In10.Cu" signal "GND4")
		(24 "In11.Cu" signal "IN4")
		(26 "In12.Cu" signal "GND5")
		(28 "In13.Cu" signal "IN5")
		(30 "In14.Cu" signal "GND6")
		(32 "In15.Cu" signal "IN6")
		(34 "In16.Cu" signal "GND7")
		(2 "B.Cu" signal "BOTTOM")
		(9 "F.Adhes" user "F.Adhesive")
		(11 "B.Adhes" user "B.Adhesive")
		(13 "F.Paste" user "Package Geometry/Pastemask Top")
		(15 "B.Paste" user "Package Geometry/Pastemask Bottom")
		(5 "F.SilkS" user "Ref Des/Silkscreen Top")
		(7 "B.SilkS" user "Ref Des/Silkscreen Bottom")
		(1 "F.Mask" user "Board Geometry/Soldermask Top")
		(3 "B.Mask" user "Board Geometry/Soldermask Bottom")
		(17 "Dwgs.User" user "User.Drawings")
		(19 "Cmts.User" user "User.Comments")
		(21 "Eco1.User" user "User.Eco1")
		(23 "Eco2.User" user "User.Eco2")
		(25 "Edge.Cuts" user "Board Geometry/Outline")
		(27 "Margin" user)
		(31 "F.CrtYd" user "Package Geometry/Place Bound Top")
		(29 "B.CrtYd" user "Package Geometry/Place Bound Bottom")
		(35 "F.Fab" user "Ref Des/Assembly Top")
		(33 "B.Fab" user "Ref Des/Assembly Bottom")
	)
	(footprint ""
		(layer "B.Cu")
		(at 126.478538 -386.766562 90)
		(property "Reference" "C493"
			(at 0 0 90)
			(layer "B.SilkS")
			(hide yes)
			(effects
				(font
					(size 1.27 1.27)
				)
				(justify mirror)
			)
		)
		(property "Value" ""
			(at 0 0 90)
			(layer "B.Fab")
			(effects
				(font
					(size 1.27 1.27)
				)
				(justify mirror)
			)
		)
		(duplicate_pad_numbers_are_jumpers no)
		(fp_line
			(start 0.299974 -0.150114)
			(end -0.299974 -0.150114)
			(stroke
				(width 0.1)
				(type default)
			)
			(layer "B.Fab")
		)
		(fp_line
			(start -0.299974 -0.150114)
			(end -0.299974 0.150114)
			(stroke
				(width 0.1)
				(type default)
			)
			(layer "B.Fab")
		)
		(fp_line
			(start 0.299974 0.150114)
			(end 0.299974 -0.150114)
			(stroke
				(width 0.1)
				(type default)
			)
			(layer "B.Fab")
		)
		(fp_line
			(start -0.299974 0.150114)
			(end 0.299974 0.150114)
			(stroke
				(width 0.1)
				(type default)
			)
			(layer "B.Fab")
		)
		(pad "1" smd rect
			(at 0.2667 0 270)
			(size 0.3048 0.381)
			(layers "B.Cu" "B.Mask" "B.Paste")
			(net "P0V9_CPU1_RT_2D")
		)
		(pad "2" smd rect
			(at -0.2667 0 270)
			(size 0.3048 0.381)
			(layers "B.Cu" "B.Mask" "B.Paste")
			(net "GND")
		)
	)
	(footprint ""
		(layer "B.Cu")
		(at 428.98695 -39.055548)
		(property "Reference" "R1265"
			(at 0 0 0)
			(layer "B.SilkS")
			(hide yes)
			(effects
				(font
					(size 1.27 1.27)
				)
				(justify mirror)
			)
		)
		(property "Value" ""
			(at 0 0 0)
			(layer "B.Fab")
			(effects
				(font
					(size 1.27 1.27)
				)
				(justify mirror)
			)
		)
		(duplicate_pad_numbers_are_jumpers no)
		(fp_line
			(start -0.7874 -0.4064)
			(end -0.7874 0.4064)
			(stroke
				(width 0.1524)
				(type default)
			)
			(layer "B.SilkS")
		)
		(fp_line
			(start -0.7874 0.4064)
			(end 0.7874 0.4064)
			(stroke
				(width 0.1524)
				(type default)
			)
			(layer "B.SilkS")
		)
		(fp_line
			(start 0.7874 -0.4064)
			(end -0.7874 -0.4064)
			(stroke
				(width 0.1524)
				(type default)
			)
			(layer "B.SilkS")
		)
		(fp_line
			(start 0.7874 0.4064)
			(end 0.7874 -0.4064)
			(stroke
				(width 0.1524)
				(type default)
			)
			(layer "B.SilkS")
		)
		(fp_line
			(start -0.67945 -0.3048)
			(end -0.67945 0.3048)
			(stroke
				(width 0.1)
				(type default)
			)
			(layer "B.Fab")
		)
		(fp_line
			(start -0.67945 0.3048)
			(end -0.120396 0.3048)
			(stroke
				(width 0.1)
				(type default)
			)
			(layer "B.Fab")
		)
		(fp_line
			(start -0.12065 -0.3048)
			(end -0.67945 -0.3048)
			(stroke
				(width 0.1)
				(type default)
			)
			(layer "B.Fab")
		)
		(fp_line
			(start -0.12065 -0.2794)
			(end -0.12065 -0.3048)
			(stroke
				(width 0.1)
				(type default)
			)
			(layer "B.Fab")
		)
		(fp_line
			(start -0.120396 0.2794)
			(end 0.12065 0.2794)
			(stroke
				(width 0.1)
				(type default)
			)
			(layer "B.Fab")
		)
		(fp_line
			(start -0.120396 0.3048)
			(end -0.120396 0.2794)
			(stroke
				(width 0.1)
				(type default)
			)
			(layer "B.Fab")
		)
		(fp_line
			(start 0.12065 -0.305054)
			(end 0.12065 -0.2794)
			(stroke
				(width 0.1)
				(type default)
			)
			(layer "B.Fab")
		)
		(fp_line
			(start 0.12065 -0.2794)
			(end -0.12065 -0.2794)
			(stroke
				(width 0.1)
				(type default)
			)
			(layer "B.Fab")
		)
		(fp_line
			(start 0.12065 0.2794)
			(end 0.12065 0.3048)
			(stroke
				(width 0.1)
				(type default)
			)
			(layer "B.Fab")
		)
		(fp_line
			(start 0.12065 0.3048)
			(end 0.67945 0.3048)
			(stroke
				(width 0.1)
				(type default)
			)
			(layer "B.Fab")
		)
		(fp_line
			(start 0.67945 -0.305054)
			(end 0.12065 -0.305054)
			(stroke
				(width 0.1)
				(type default)
			)
			(layer "B.Fab")
		)
		(fp_line
			(start 0.67945 0.3048)
			(end 0.67945 -0.305054)
			(stroke
				(width 0.1)
				(type default)
			)
			(layer "B.Fab")
		)
		(pad "1" smd circle
			(at 0.40005 0 180)
			(size 0 0)
			(layers "B.Cu" "B.Mask" "B.Paste")
			(net "FM_BIOS_USB_RECOVERY")
		)
		(pad "2" smd circle
			(at -0.40005 0 180)
			(size 0 0)
			(layers "B.Cu" "B.Mask" "B.Paste")
			(net "GND")
		)
	)
	(footprint ""
		(layer "B.Cu")
		(at 412.606236 -395.148562 90)
		(property "Reference" "C777"
			(at 0 0 90)
			(layer "B.SilkS")
			(hide yes)
			(effects
				(font
					(size 1.27 1.27)
				)
				(justify mirror)
			)
		)
		(property "Value" ""
			(at 0 0 90)
			(layer "B.Fab")
			(effects
				(font
					(size 1.27 1.27)
				)
				(justify mirror)
			)
		)
		(duplicate_pad_numbers_are_jumpers no)
		(fp_line
			(start 0.299974 -0.150114)
			(end -0.299974 -0.150114)
			(stroke
				(width 0.1)
				(type default)
			)
			(layer "B.Fab")
		)
		(fp_line
			(start -0.299974 -0.150114)
			(end -0.299974 0.150114)
			(stroke
				(width 0.1)
				(type default)
			)
			(layer "B.Fab")
		)
		(fp_line
			(start 0.299974 0.150114)
			(end 0.299974 -0.150114)
			(stroke
				(width 0.1)
				(type default)
			)
			(layer "B.Fab")
		)
		(fp_line
			(start -0.299974 0.150114)
			(end 0.299974 0.150114)
			(stroke
				(width 0.1)
				(type default)
			)
			(layer "B.Fab")
		)
		(pad "1" smd rect
			(at 0.2667 0 270)
			(size 0.3048 0.381)
			(layers "B.Cu" "B.Mask" "B.Paste")
			(net "P1V8_CPU0_RT2_1A")
		)
		(pad "2" smd rect
			(at -0.2667 0 270)
			(size 0.3048 0.381)
			(layers "B.Cu" "B.Mask" "B.Paste")
			(net "GND")
		)
	)
	(footprint ""
		(layer "B.Cu")
		(at 51.118516 -388.011162 -90)
		(property "Reference" "C260"
			(at 0 0 90)
			(layer "B.SilkS")
			(hide yes)
			(effects
				(font
					(size 1.27 1.27)
				)
				(justify mirror)
			)
		)
		(property "Value" ""
			(at 0 0 90)
			(layer "B.Fab")
			(effects
				(font
					(size 1.27 1.27)
				)
				(justify mirror)
			)
		)
		(duplicate_pad_numbers_are_jumpers no)
		(fp_line
			(start -0.299974 0.150114)
			(end 0.299974 0.150114)
			(stroke
				(width 0.1)
				(type default)
			)
			(layer "B.Fab")
		)
		(fp_line
			(start 0.299974 0.150114)
			(end 0.299974 -0.150114)
			(stroke
				(width 0.1)
				(type default)
			)
			(layer "B.Fab")
		)
		(fp_line
			(start -0.299974 -0.150114)
			(end -0.299974 0.150114)
			(stroke
				(width 0.1)
				(type default)
			)
			(layer "B.Fab")
		)
		(fp_line
			(start 0.299974 -0.150114)
			(end -0.299974 -0.150114)
			(stroke
				(width 0.1)
				(type default)
			)
			(layer "B.Fab")
		)
		(pad "1" smd rect
			(at 0.2667 0 90)
			(size 0.3048 0.381)
			(layers "B.Cu" "B.Mask" "B.Paste")
			(net "P0V9_CPU1_RT0_2A")
		)
		(pad "2" smd rect
			(at -0.2667 0 90)
			(size 0.3048 0.381)
			(layers "B.Cu" "B.Mask" "B.Paste")
			(net "GND")
		)
	)
	(footprint ""
		(layer "B.Cu")
		(at 63.118492 -388.011162 -90)
		(property "Reference" "C228"
			(at 0 0 90)
			(layer "B.SilkS")
			(hide yes)
			(effects
				(font
					(size 1.27 1.27)
				)
				(justify mirror)
			)
		)
		(property "Value" ""
			(at 0 0 90)
			(layer "B.Fab")
			(effects
				(font
					(size 1.27 1.27)
				)
				(justify mirror)
			)
		)
		(duplicate_pad_numbers_are_jumpers no)
		(fp_line
			(start -0.299974 0.150114)
			(end 0.299974 0.150114)
			(stroke
				(width 0.1)
				(type default)
			)
			(layer "B.Fab")
		)
		(fp_line
			(start 0.299974 0.150114)
			(end 0.299974 -0.150114)
			(stroke
				(width 0.1)
				(type default)
			)
			(layer "B.Fab")
		)
		(fp_line
			(start -0.299974 -0.150114)
			(end -0.299974 0.150114)
			(stroke
				(width 0.1)
				(type default)
			)
			(layer "B.Fab")
		)
		(fp_line
			(start 0.299974 -0.150114)
			(end -0.299974 -0.150114)
			(stroke
				(width 0.1)
				(type default)
			)
			(layer "B.Fab")
		)
		(pad "1" smd rect
			(at 0.2667 0 90)
			(size 0.3048 0.381)
			(layers "B.Cu" "B.Mask" "B.Paste")
			(net "P0V9_CPU1_RT0_2A")
		)
		(pad "2" smd rect
			(at -0.2667 0 90)
			(size 0.3048 0.381)
			(layers "B.Cu" "B.Mask" "B.Paste")
			(net "GND")
		)
	)
)
